# BASEBOARD_FAB2 (Tioga Pass) — schematic netlist excerpt (pin names and nets, part order shuffled) for the footprints in the layout excerpt that follows; sources: Cadence DE-HDL packaged netlist, KiCad conversion of Wiwynn_Tioga_Pass_MB.brd

C2P8  CAP_A  0.01UF 25V 10% X7R  pkg 0402V  page 192 : A = P3V3_STBY ; B = GND
C3M14  CAP  0.22UF 16V 10% X7R  pkg 0402  page 105 : A = P3E_CPU0_PE1_PCH_R_RXN<13> ; B = P3E_CPU0_PE1_PCH_RXN<13>
R25W86  RES  22.1 1.0% CHIP  pkg 0402  page 147 : A = RMII_BMC_OCP_TXD0_R ; B = RMII_BMC_OCP_TXD0

(kicad_pcb
	(version 20260206)
	(generator "pcbnew")
	(generator_version "10.0")
	(general
		(thickness 1.6)
		(legacy_teardrops no)
	)
	(paper "A4")
	(title_block
		(title "Wiwynn_Tioga_Pass_MB.brd")
		(comment 1 "Tioga Pass / footprints 2807-2809 of 4770")
	)
	(layers
		(0 "F.Cu" signal "TOP")
		(4 "In1.Cu" signal "L2GND")
		(6 "In2.Cu" signal "L3")
		(8 "In3.Cu" signal "L4GND")
		(10 "In4.Cu" signal "L5")
		(12 "In5.Cu" signal "L6GND")
		(14 "In6.Cu" signal "L7VCC")
		(16 "In7.Cu" signal "L8VCC")
		(18 "In8.Cu" signal "L9GND")
		(20 "In9.Cu" signal "L10")
		(22 "In10.Cu" signal "L11GND")
		(24 "In11.Cu" signal "L12")
		(26 "In12.Cu" signal "L13GND")
		(2 "B.Cu" signal "BOTTOM")
		(9 "F.Adhes" user "F.Adhesive")
		(11 "B.Adhes" user "B.Adhesive")
		(13 "F.Paste" user "Package Geometry/Pastemask Top")
		(15 "B.Paste" user "Package Geometry/Pastemask Bottom")
		(5 "F.SilkS" user "Ref Des/Silkscreen Top")
		(7 "B.SilkS" user "Ref Des/Silkscreen Bottom")
		(1 "F.Mask" user "Board Geometry/Soldermask Top")
		(3 "B.Mask" user "Board Geometry/Soldermask Bottom")
		(17 "Dwgs.User" user "User.Drawings")
		(19 "Cmts.User" user "User.Comments")
		(21 "Eco1.User" user "User.Eco1")
		(23 "Eco2.User" user "User.Eco2")
		(25 "Edge.Cuts" user "Board Geometry/Outline")
		(27 "Margin" user)
		(31 "F.CrtYd" user "Package Geometry/Place Bound Top")
		(29 "B.CrtYd" user "Package Geometry/Place Bound Bottom")
		(35 "F.Fab" user "Ref Des/Assembly Top")
		(33 "B.Fab" user "Ref Des/Assembly Bottom")
	)
	(footprint ""
		(layer "B.Cu")
		(at 377.144788 -70.695058)
		(property "Reference" "C2P8"
			(at 0 0 0)
			(layer "B.SilkS")
			(hide yes)
			(effects
				(font
					(size 1.27 1.27)
				)
				(justify mirror)
			)
		)
		(property "Value" ""
			(at 0 0 0)
			(layer "B.Fab")
			(effects
				(font
					(size 1.27 1.27)
				)
				(justify mirror)
			)
		)
		(duplicate_pad_numbers_are_jumpers no)
		(fp_rect
			(start 0.2794 0.9144)
			(end -0.2794 -0.1143)
			(stroke
				(width 0)
				(type default)
			)
			(fill no)
			(layer "B.CrtYd")
		)
		(fp_line
			(start -0.2794 -0.1143)
			(end -0.2794 0.9144)
			(stroke
				(width 0.1)
				(type default)
			)
			(layer "B.Fab")
		)
		(fp_line
			(start -0.2794 0.9144)
			(end 0.2794 0.9144)
			(stroke
				(width 0.1)
				(type default)
			)
			(layer "B.Fab")
		)
		(fp_line
			(start 0.2794 -0.1143)
			(end -0.2794 -0.1143)
			(stroke
				(width 0.1)
				(type default)
			)
			(layer "B.Fab")
		)
		(fp_line
			(start 0.2794 0.9144)
			(end 0.2794 -0.1143)
			(stroke
				(width 0.1)
				(type default)
			)
			(layer "B.Fab")
		)
		(pad "1" smd custom
			(at 0 0 270)
			(size 0.10414 0.10414)
			(layers "B.Cu" "B.Mask" "B.Paste")
			(net "P3V3_STBY")
			(options
				(clearance outline)
				(anchor circle)
			)
			(primitives
				(gr_poly
					(pts
						(xy -0.20828 -0.08636) (xy -0.20828 0.08636) (xy -0.08636 0.20828) (xy 0.086614 0.20828) (xy 0.20828 0.086614)
						(xy 0.20828 -0.08636) (xy 0.08636 -0.20828) (xy -0.08636 -0.20828)
					)
					(width 0)
					(fill yes)
				)
			)
		)
		(pad "2" smd custom
			(at 0 0.8001 270)
			(size 0.10414 0.10414)
			(layers "B.Cu" "B.Mask" "B.Paste")
			(net "GND")
			(options
				(clearance outline)
				(anchor circle)
			)
			(primitives
				(gr_poly
					(pts
						(xy -0.20828 -0.08636) (xy -0.20828 0.08636) (xy -0.08636 0.20828) (xy 0.086614 0.20828) (xy 0.20828 0.086614)
						(xy 0.20828 -0.08636) (xy 0.08636 -0.20828) (xy -0.08636 -0.20828)
					)
					(width 0)
					(fill yes)
				)
			)
		)
		(zone
			(layer "B.Cu")
			(hatch none 0.5)
			(connect_pads
				(clearance 0)
			)
			(min_thickness 0.25)
			(keepout
				(tracks allowed)
				(vias not_allowed)
				(pads allowed)
				(copperpour not_allowed)
				(footprints allowed)
			)
			(placement
				(enabled no)
				(sheetname "")
			)
			(fill
				(thermal_gap 0.5)
				(thermal_bridge_width 0.5)
				(island_removal_mode 0)
			)
			(polygon
				(pts
					(xy 377.232418 -70.485508) (xy 377.232418 -70.104508) (xy 377.057158 -70.104508) (xy 377.056904 -70.485508)
				)
			)
		)
		(zone
			(layer "B.Cu")
			(hatch none 0.5)
			(connect_pads
				(clearance 0)
			)
			(min_thickness 0.25)
			(keepout
				(tracks not_allowed)
				(vias allowed)
				(pads allowed)
				(copperpour not_allowed)
				(footprints allowed)
			)
			(placement
				(enabled no)
				(sheetname "")
			)
			(fill
				(thermal_gap 0.5)
				(thermal_bridge_width 0.5)
				(island_removal_mode 0)
			)
			(polygon
				(pts
					(xy 377.232418 -70.485508) (xy 377.232418 -70.104508) (xy 377.057158 -70.104508) (xy 377.056904 -70.485508)
				)
			)
		)
	)
	(footprint ""
		(layer "B.Cu")
		(at 349.489014 -122.459242 -90)
		(property "Reference" "C3M14"
			(at 0 0 90)
			(layer "B.SilkS")
			(hide yes)
			(effects
				(font
					(size 1.27 1.27)
				)
				(justify mirror)
			)
		)
		(property "Value" ""
			(at 0 0 90)
			(layer "B.Fab")
			(effects
				(font
					(size 1.27 1.27)
				)
				(justify mirror)
			)
		)
		(duplicate_pad_numbers_are_jumpers no)
		(fp_poly
			(pts
				(xy -0.3048 -0.1016) (xy -0.3048 0.9906) (xy 0.3048 0.9906) (xy 0.3048 -0.1016)
			)
			(stroke
				(width 0)
				(type default)
			)
			(fill no)
			(layer "B.CrtYd")
		)
		(fp_line
			(start -0.3048 0.9906)
			(end -0.3048 -0.1016)
			(stroke
				(width 0.1)
				(type default)
			)
			(layer "B.Fab")
		)
		(fp_line
			(start 0.3048 0.9906)
			(end -0.3048 0.9906)
			(stroke
				(width 0.1)
				(type default)
			)
			(layer "B.Fab")
		)
		(fp_line
			(start -0.3048 -0.1016)
			(end 0.3048 -0.1016)
			(stroke
				(width 0.1)
				(type default)
			)
			(layer "B.Fab")
		)
		(fp_line
			(start 0.3048 -0.1016)
			(end 0.3048 0.9906)
			(stroke
				(width 0.1)
				(type default)
			)
			(layer "B.Fab")
		)
		(pad "1" smd rect
			(at 0 0 90)
			(size 0.508 0.508)
			(layers "B.Cu" "B.Mask" "B.Paste")
			(net "P3E_CPU0_PE1_PCH_R_RXN<13>")
		)
		(pad "2" smd rect
			(at 0 0.889 90)
			(size 0.508 0.508)
			(layers "B.Cu" "B.Mask" "B.Paste")
			(net "P3E_CPU0_PE1_PCH_RXN<13>")
		)
		(zone
			(layer "B.Cu")
			(hatch none 0.5)
			(connect_pads
				(clearance 0)
			)
			(min_thickness 0.25)
			(keepout
				(tracks not_allowed)
				(vias allowed)
				(pads allowed)
				(copperpour not_allowed)
				(footprints allowed)
			)
			(placement
				(enabled no)
				(sheetname "")
			)
			(fill
				(thermal_gap 0.5)
				(thermal_bridge_width 0.5)
				(island_removal_mode 0)
			)
			(polygon
				(pts
					(xy 348.854014 -122.205242) (xy 348.854014 -122.713242) (xy 349.235014 -122.713242) (xy 349.235014 -122.205242)
				)
			)
		)
		(zone
			(layer "B.Cu")
			(hatch none 0.5)
			(connect_pads
				(clearance 0)
			)
			(min_thickness 0.25)
			(keepout
				(tracks allowed)
				(vias not_allowed)
				(pads allowed)
				(copperpour not_allowed)
				(footprints allowed)
			)
			(placement
				(enabled no)
				(sheetname "")
			)
			(fill
				(thermal_gap 0.5)
				(thermal_bridge_width 0.5)
				(island_removal_mode 0)
			)
			(polygon
				(pts
					(xy 349.235014 -122.205242) (xy 349.235014 -122.713242) (xy 348.854014 -122.713242) (xy 348.854014 -122.205242)
				)
			)
		)
	)
	(footprint ""
		(layer "B.Cu")
		(at 403.352 -36.068)
		(property "Reference" "R25W86"
			(at 0.8382 -0.67818 0)
			(unlocked yes)
			(layer "B.SilkS")
			(effects
				(font
					(size 0.4064 0.254)
					(thickness 0.1524)
				)
				(justify left mirror)
			)
		)
		(property "Value" ""
			(at 0 0 0)
			(layer "B.Fab")
			(effects
				(font
					(size 1.27 1.27)
				)
				(justify mirror)
			)
		)
		(duplicate_pad_numbers_are_jumpers no)
		(fp_poly
			(pts
				(xy 0.2794 -0.1016) (xy -0.2794 -0.1016) (xy -0.2794 0.9906) (xy 0.2794 0.9906)
			)
			(stroke
				(width 0)
				(type default)
			)
			(fill no)
			(layer "B.CrtYd")
		)
		(fp_line
			(start -0.2794 -0.1016)
			(end 0.2794 -0.1016)
			(stroke
				(width 0.1)
				(type default)
			)
			(layer "B.Fab")
		)
		(fp_line
			(start -0.2794 0.9906)
			(end -0.2794 -0.1016)
			(stroke
				(width 0.1)
				(type default)
			)
			(layer "B.Fab")
		)
		(fp_line
			(start 0.2794 -0.1016)
			(end 0.2794 0.9906)
			(stroke
				(width 0.1)
				(type default)
			)
			(layer "B.Fab")
		)
		(fp_line
			(start 0.2794 0.9906)
			(end -0.2794 0.9906)
			(stroke
				(width 0.1)
				(type default)
			)
			(layer "B.Fab")
		)
		(pad "1" smd rect
			(at 0 0 180)
			(size 0.508 0.508)
			(layers "B.Cu" "B.Mask" "B.Paste")
			(net "RMII_BMC_OCP_TXD0_R")
		)
		(pad "2" smd rect
			(at 0 0.889 180)
			(size 0.508 0.508)
			(layers "B.Cu" "B.Mask" "B.Paste")
			(net "RMII_BMC_OCP_TXD0")
		)
		(zone
			(layer "B.Cu")
			(hatch none 0.5)
			(connect_pads
				(clearance 0)
			)
			(min_thickness 0.25)
			(keepout
				(tracks allowed)
				(vias not_allowed)
				(pads allowed)
				(copperpour not_allowed)
				(footprints allowed)
			)
			(placement
				(enabled no)
				(sheetname "")
			)
			(fill
				(thermal_gap 0.5)
				(thermal_bridge_width 0.5)
				(island_removal_mode 0)
			)
			(polygon
				(pts
					(xy 403.606 -35.814) (xy 403.098 -35.814) (xy 403.098 -35.433) (xy 403.606 -35.433)
				)
			)
		)
		(zone
			(layer "B.Cu")
			(hatch none 0.5)
			(connect_pads
				(clearance 0)
			)
			(min_thickness 0.25)
			(keepout
				(tracks not_allowed)
				(vias allowed)
				(pads allowed)
				(copperpour not_allowed)
				(footprints allowed)
			)
			(placement
				(enabled no)
				(sheetname "")
			)
			(fill
				(thermal_gap 0.5)
				(thermal_bridge_width 0.5)
				(island_removal_mode 0)
			)
			(polygon
				(pts
					(xy 403.606 -35.433) (xy 403.098 -35.433) (xy 403.098 -35.814) (xy 403.606 -35.814)
				)
			)
		)
	)
)
